FILE_TYPE = MULTI_PHYS_TABLE;

PART 'MC74VHC1G32DTT1G'

{========================================================================================}
:VALUE              | PART_TYPE | MATERIAL | PART_NUMBER    = STANDARD | LIFECYCLE      | PART_NUMBER   | JEDEC_TYPE           | DESCRIPTION                             | MANUFTR | MANUF_PN           | RD_CMPLS_LVL | CMPLS_LVL | FROM_PJ      | CLASS | DIP_SMD | DATA                       | EE_CHECK_LIST | FP_ECN | PSL | CREATOR | STATUS | MSD | ESD_CDM | ESD_HBM | ESD_MM | PIN_LENGTH_SHORT_PIN | PIN_LENGTH_LONG_PIN | CREATEDAY  ;
{========================================================================================}
 'MC74VHC1G32DTT1G' | 'SMLF'    | 'IC'     | 'AL001G32031'(!) = ''       | ''               | 'AL001G32031' |'SOT23-5_0-95_3X1-5'| 'IC OTHER (5P)MC74VHC1G32DTT1G(SOT-23)' | 'ONS'   | 'MC74VHC1G32DTT1G' | 'EP(V1)'     | 'EP(V1)'  | 'F0T-FISHER' | 'IC'  | ''      | 'ONS_MC74VHC1G32DTT1G.pdf' | ''            | ''     | ''  | ''      | ''     | ''  | ''      | ''      | ''     | '0 MILS'             | '0 MILS'            | '20211006'
 'MC74VHC1G32DTT1G' | 'SMLF'    | 'EMPTY'  | 'AL001G32031'(!) = ''       | ''               | 'AL001G32031' |'SOT23-5_0-95_3X1-5'| 'IC OTHER (5P)MC74VHC1G32DTT1G(SOT-23)' | 'ONS'   | 'MC74VHC1G32DTT1G' | 'EP(V1)'     | 'EP(V1)'  | 'F0T-FISHER' | 'IC'  | ''      | 'ONS_MC74VHC1G32DTT1G.pdf' | ''            | ''     | ''  | ''      | ''     | ''  | ''      | ''      | ''     | '0 MILS'             | '0 MILS'            | '20211006'

END_PART

END.

